(kicad_pcb
	(version 20260206)
	(generator "pcbnew")
	(generator_version "10.0")
	(general
		(thickness 1.6)
		(legacy_teardrops no)
	)
	(paper "A4")
	(title_block
		(title "03242023_DA0F0TMBIJ0_F0T_Motherboard_J_brd_V01_OCP.brd")
		(comment 1 "Grand Teton / footprints 2026-2031 of 6105")
	)
	(layers
		(0 "F.Cu" signal "TOP")
		(4 "In1.Cu" signal "GND")
		(6 "In2.Cu" signal "IN1")
		(8 "In3.Cu" signal "GND1")
		(10 "In4.Cu" signal "IN2")
		(12 "In5.Cu" signal "GND2")
		(14 "In6.Cu" signal "IN3")
		(16 "In7.Cu" signal "GND3")
		(18 "In8.Cu" signal "VCC")
		(20 "In9.Cu" signal "VCC1")
		(22 "In10.Cu" signal "GND4")
		(24 "In11.Cu" signal "IN4")
		(26 "In12.Cu" signal "GND5")
		(28 "In13.Cu" signal "IN5")
		(30 "In14.Cu" signal "GND6")
		(32 "In15.Cu" signal "IN6")
		(34 "In16.Cu" signal "GND7")
		(2 "B.Cu" signal "BOTTOM")
		(9 "F.Adhes" user "F.Adhesive")
		(11 "B.Adhes" user "B.Adhesive")
		(13 "F.Paste" user "Package Geometry/Pastemask Top")
		(15 "B.Paste" user "Package Geometry/Pastemask Bottom")
		(5 "F.SilkS" user "Ref Des/Silkscreen Top")
		(7 "B.SilkS" user "Ref Des/Silkscreen Bottom")
		(1 "F.Mask" user "Board Geometry/Soldermask Top")
		(3 "B.Mask" user "Board Geometry/Soldermask Bottom")
		(17 "Dwgs.User" user "User.Drawings")
		(19 "Cmts.User" user "User.Comments")
		(21 "Eco1.User" user "User.Eco1")
		(23 "Eco2.User" user "User.Eco2")
		(25 "Edge.Cuts" user "Board Geometry/Outline")
		(27 "Margin" user)
		(31 "F.CrtYd" user "Package Geometry/Place Bound Top")
		(29 "B.CrtYd" user "Package Geometry/Place Bound Bottom")
		(35 "F.Fab" user "Ref Des/Assembly Top")
		(33 "B.Fab" user "Ref Des/Assembly Bottom")
	)
	(footprint ""
		(layer "F.Cu")
		(at 197.876668 -76.016866)
		(property "Reference" "R1350"
			(at 0 0 0)
			(layer "F.SilkS")
			(hide yes)
			(effects
				(font
					(size 1.27 1.27)
				)
			)
		)
		(property "Value" ""
			(at 0 0 0)
			(layer "F.Fab")
			(effects
				(font
					(size 1.27 1.27)
				)
			)
		)
		(duplicate_pad_numbers_are_jumpers no)
		(fp_line
			(start -0.7874 -0.4064)
			(end 0.7874 -0.4064)
			(stroke
				(width 0.1524)
				(type default)
			)
			(layer "F.SilkS")
		)
		(fp_line
			(start -0.7874 0.4064)
			(end -0.7874 -0.4064)
			(stroke
				(width 0.1524)
				(type default)
			)
			(layer "F.SilkS")
		)
		(fp_line
			(start 0.7874 -0.4064)
			(end 0.7874 0.4064)
			(stroke
				(width 0.1524)
				(type default)
			)
			(layer "F.SilkS")
		)
		(fp_line
			(start 0.7874 0.4064)
			(end -0.7874 0.4064)
			(stroke
				(width 0.1524)
				(type default)
			)
			(layer "F.SilkS")
		)
		(fp_line
			(start -0.67945 -0.305054)
			(end -0.12065 -0.305054)
			(stroke
				(width 0.1)
				(type default)
			)
			(layer "F.Fab")
		)
		(fp_line
			(start -0.67945 0.3048)
			(end -0.67945 -0.305054)
			(stroke
				(width 0.1)
				(type default)
			)
			(layer "F.Fab")
		)
		(fp_line
			(start -0.12065 -0.305054)
			(end -0.12065 -0.2794)
			(stroke
				(width 0.1)
				(type default)
			)
			(layer "F.Fab")
		)
		(fp_line
			(start -0.12065 -0.2794)
			(end 0.12065 -0.2794)
			(stroke
				(width 0.1)
				(type default)
			)
			(layer "F.Fab")
		)
		(fp_line
			(start -0.12065 0.2794)
			(end -0.12065 0.3048)
			(stroke
				(width 0.1)
				(type default)
			)
			(layer "F.Fab")
		)
		(fp_line
			(start -0.12065 0.3048)
			(end -0.67945 0.3048)
			(stroke
				(width 0.1)
				(type default)
			)
			(layer "F.Fab")
		)
		(fp_line
			(start 0.120396 0.2794)
			(end -0.12065 0.2794)
			(stroke
				(width 0.1)
				(type default)
			)
			(layer "F.Fab")
		)
		(fp_line
			(start 0.120396 0.3048)
			(end 0.120396 0.2794)
			(stroke
				(width 0.1)
				(type default)
			)
			(layer "F.Fab")
		)
		(fp_line
			(start 0.12065 -0.3048)
			(end 0.67945 -0.3048)
			(stroke
				(width 0.1)
				(type default)
			)
			(layer "F.Fab")
		)
		(fp_line
			(start 0.12065 -0.2794)
			(end 0.12065 -0.3048)
			(stroke
				(width 0.1)
				(type default)
			)
			(layer "F.Fab")
		)
		(fp_line
			(start 0.67945 -0.3048)
			(end 0.67945 0.3048)
			(stroke
				(width 0.1)
				(type default)
			)
			(layer "F.Fab")
		)
		(fp_line
			(start 0.67945 0.3048)
			(end 0.120396 0.3048)
			(stroke
				(width 0.1)
				(type default)
			)
			(layer "F.Fab")
		)
		(pad "1" smd circle
			(at -0.40005 0)
			(size 0 0)
			(layers "F.Cu" "F.Mask" "F.Paste")
			(net "RMII_OCP_BMC_CRSDV")
		)
		(pad "2" smd circle
			(at 0.40005 0)
			(size 0 0)
			(layers "F.Cu" "F.Mask" "F.Paste")
			(net "GND")
		)
	)
	(footprint ""
		(layer "F.Cu")
		(at 366.637824 -354.652326 180)
		(property "Reference" "R2408"
			(at 0 0 180)
			(layer "F.SilkS")
			(hide yes)
			(effects
				(font
					(size 1.27 1.27)
				)
			)
		)
		(property "Value" ""
			(at 0 0 180)
			(layer "F.Fab")
			(effects
				(font
					(size 1.27 1.27)
				)
			)
		)
		(duplicate_pad_numbers_are_jumpers no)
		(fp_line
			(start 0.7874 0.4064)
			(end -0.7874 0.4064)
			(stroke
				(width 0.1524)
				(type default)
			)
			(layer "F.SilkS")
		)
		(fp_line
			(start 0.7874 -0.4064)
			(end 0.7874 0.4064)
			(stroke
				(width 0.1524)
				(type default)
			)
			(layer "F.SilkS")
		)
		(fp_line
			(start -0.7874 0.4064)
			(end -0.7874 -0.4064)
			(stroke
				(width 0.1524)
				(type default)
			)
			(layer "F.SilkS")
		)
		(fp_line
			(start -0.7874 -0.4064)
			(end 0.7874 -0.4064)
			(stroke
				(width 0.1524)
				(type default)
			)
			(layer "F.SilkS")
		)
		(fp_line
			(start 0.67945 0.3048)
			(end 0.120396 0.3048)
			(stroke
				(width 0.1)
				(type default)
			)
			(layer "F.Fab")
		)
		(fp_line
			(start 0.67945 -0.3048)
			(end 0.67945 0.3048)
			(stroke
				(width 0.1)
				(type default)
			)
			(layer "F.Fab")
		)
		(fp_line
			(start 0.12065 -0.2794)
			(end 0.12065 -0.3048)
			(stroke
				(width 0.1)
				(type default)
			)
			(layer "F.Fab")
		)
		(fp_line
			(start 0.12065 -0.3048)
			(end 0.67945 -0.3048)
			(stroke
				(width 0.1)
				(type default)
			)
			(layer "F.Fab")
		)
		(fp_line
			(start 0.120396 0.3048)
			(end 0.120396 0.2794)
			(stroke
				(width 0.1)
				(type default)
			)
			(layer "F.Fab")
		)
		(fp_line
			(start 0.120396 0.2794)
			(end -0.12065 0.2794)
			(stroke
				(width 0.1)
				(type default)
			)
			(layer "F.Fab")
		)
		(fp_line
			(start -0.12065 0.3048)
			(end -0.67945 0.3048)
			(stroke
				(width 0.1)
				(type default)
			)
			(layer "F.Fab")
		)
		(fp_line
			(start -0.12065 0.2794)
			(end -0.12065 0.3048)
			(stroke
				(width 0.1)
				(type default)
			)
			(layer "F.Fab")
		)
		(fp_line
			(start -0.12065 -0.2794)
			(end 0.12065 -0.2794)
			(stroke
				(width 0.1)
				(type default)
			)
			(layer "F.Fab")
		)
		(fp_line
			(start -0.12065 -0.305054)
			(end -0.12065 -0.2794)
			(stroke
				(width 0.1)
				(type default)
			)
			(layer "F.Fab")
		)
		(fp_line
			(start -0.67945 0.3048)
			(end -0.67945 -0.305054)
			(stroke
				(width 0.1)
				(type default)
			)
			(layer "F.Fab")
		)
		(fp_line
			(start -0.67945 -0.305054)
			(end -0.12065 -0.305054)
			(stroke
				(width 0.1)
				(type default)
			)
			(layer "F.Fab")
		)
		(pad "1" smd circle
			(at -0.40005 0 180)
			(size 0 0)
			(layers "F.Cu" "F.Mask" "F.Paste")
			(net "PWRGD_PVPP_HBM_CPU0_R")
		)
		(pad "2" smd circle
			(at 0.40005 0 180)
			(size 0 0)
			(layers "F.Cu" "F.Mask" "F.Paste")
			(net "PWRGD_PVPP_HBM_CPU0")
		)
	)
	(footprint ""
		(layer "F.Cu")
		(at 355.8286 -403.9108)
		(property "Reference" "R4730"
			(at 0 0 0)
			(layer "F.SilkS")
			(hide yes)
			(effects
				(font
					(size 1.27 1.27)
				)
			)
		)
		(property "Value" ""
			(at 0 0 0)
			(layer "F.Fab")
			(effects
				(font
					(size 1.27 1.27)
				)
			)
		)
		(duplicate_pad_numbers_are_jumpers no)
		(fp_line
			(start -0.7874 -0.4064)
			(end 0.7874 -0.4064)
			(stroke
				(width 0.1524)
				(type default)
			)
			(layer "F.SilkS")
		)
		(fp_line
			(start -0.7874 0.4064)
			(end -0.7874 -0.4064)
			(stroke
				(width 0.1524)
				(type default)
			)
			(layer "F.SilkS")
		)
		(fp_line
			(start 0.7874 -0.4064)
			(end 0.7874 0.4064)
			(stroke
				(width 0.1524)
				(type default)
			)
			(layer "F.SilkS")
		)
		(fp_line
			(start 0.7874 0.4064)
			(end -0.7874 0.4064)
			(stroke
				(width 0.1524)
				(type default)
			)
			(layer "F.SilkS")
		)
		(fp_line
			(start -0.67945 -0.305054)
			(end -0.12065 -0.305054)
			(stroke
				(width 0.1)
				(type default)
			)
			(layer "F.Fab")
		)
		(fp_line
			(start -0.67945 0.3048)
			(end -0.67945 -0.305054)
			(stroke
				(width 0.1)
				(type default)
			)
			(layer "F.Fab")
		)
		(fp_line
			(start -0.12065 -0.305054)
			(end -0.12065 -0.2794)
			(stroke
				(width 0.1)
				(type default)
			)
			(layer "F.Fab")
		)
		(fp_line
			(start -0.12065 -0.2794)
			(end 0.12065 -0.2794)
			(stroke
				(width 0.1)
				(type default)
			)
			(layer "F.Fab")
		)
		(fp_line
			(start -0.12065 0.2794)
			(end -0.12065 0.3048)
			(stroke
				(width 0.1)
				(type default)
			)
			(layer "F.Fab")
		)
		(fp_line
			(start -0.12065 0.3048)
			(end -0.67945 0.3048)
			(stroke
				(width 0.1)
				(type default)
			)
			(layer "F.Fab")
		)
		(fp_line
			(start 0.120396 0.2794)
			(end -0.12065 0.2794)
			(stroke
				(width 0.1)
				(type default)
			)
			(layer "F.Fab")
		)
		(fp_line
			(start 0.120396 0.3048)
			(end 0.120396 0.2794)
			(stroke
				(width 0.1)
				(type default)
			)
			(layer "F.Fab")
		)
		(fp_line
			(start 0.12065 -0.3048)
			(end 0.67945 -0.3048)
			(stroke
				(width 0.1)
				(type default)
			)
			(layer "F.Fab")
		)
		(fp_line
			(start 0.12065 -0.2794)
			(end 0.12065 -0.3048)
			(stroke
				(width 0.1)
				(type default)
			)
			(layer "F.Fab")
		)
		(fp_line
			(start 0.67945 -0.3048)
			(end 0.67945 0.3048)
			(stroke
				(width 0.1)
				(type default)
			)
			(layer "F.Fab")
		)
		(fp_line
			(start 0.67945 0.3048)
			(end 0.120396 0.3048)
			(stroke
				(width 0.1)
				(type default)
			)
			(layer "F.Fab")
		)
		(pad "1" smd circle
			(at -0.40005 0)
			(size 0 0)
			(layers "F.Cu" "F.Mask" "F.Paste")
			(net "P3V3_AUX")
		)
		(pad "2" smd circle
			(at 0.40005 0)
			(size 0 0)
			(layers "F.Cu" "F.Mask" "F.Paste")
			(net "PRSNT_CABLE_SWB_B2_N")
		)
	)
	(footprint ""
		(layer "F.Cu")
		(at 134.225538 -342.726264 -90)
		(property "Reference" "PC481_P1_8"
			(at 0 0 270)
			(layer "F.SilkS")
			(hide yes)
			(effects
				(font
					(size 1.27 1.27)
				)
			)
		)
		(property "Value" ""
			(at 0 0 270)
			(layer "F.Fab")
			(effects
				(font
					(size 1.27 1.27)
				)
			)
		)
		(duplicate_pad_numbers_are_jumpers no)
		(fp_line
			(start -0.7874 0.4064)
			(end -0.7874 -0.4064)
			(stroke
				(width 0.1524)
				(type default)
			)
			(layer "F.SilkS")
		)
		(fp_line
			(start 0.7874 0.4064)
			(end -0.7874 0.4064)
			(stroke
				(width 0.1524)
				(type default)
			)
			(layer "F.SilkS")
		)
		(fp_line
			(start -0.7874 -0.4064)
			(end 0.7874 -0.4064)
			(stroke
				(width 0.1524)
				(type default)
			)
			(layer "F.SilkS")
		)
		(fp_line
			(start 0.7874 -0.4064)
			(end 0.7874 0.4064)
			(stroke
				(width 0.1524)
				(type default)
			)
			(layer "F.SilkS")
		)
		(fp_line
			(start -0.67945 0.3048)
			(end -0.67945 -0.305054)
			(stroke
				(width 0.1)
				(type default)
			)
			(layer "F.Fab")
		)
		(fp_line
			(start -0.12065 0.3048)
			(end -0.67945 0.3048)
			(stroke
				(width 0.1)
				(type default)
			)
			(layer "F.Fab")
		)
		(fp_line
			(start 0.120396 0.3048)
			(end 0.120396 0.2794)
			(stroke
				(width 0.1)
				(type default)
			)
			(layer "F.Fab")
		)
		(fp_line
			(start 0.67945 0.3048)
			(end 0.120396 0.3048)
			(stroke
				(width 0.1)
				(type default)
			)
			(layer "F.Fab")
		)
		(fp_line
			(start -0.12065 0.2794)
			(end -0.12065 0.3048)
			(stroke
				(width 0.1)
				(type default)
			)
			(layer "F.Fab")
		)
		(fp_line
			(start 0.120396 0.2794)
			(end -0.12065 0.2794)
			(stroke
				(width 0.1)
				(type default)
			)
			(layer "F.Fab")
		)
		(fp_line
			(start -0.12065 -0.2794)
			(end 0.12065 -0.2794)
			(stroke
				(width 0.1)
				(type default)
			)
			(layer "F.Fab")
		)
		(fp_line
			(start 0.12065 -0.2794)
			(end 0.12065 -0.3048)
			(stroke
				(width 0.1)
				(type default)
			)
			(layer "F.Fab")
		)
		(fp_line
			(start 0.12065 -0.3048)
			(end 0.67945 -0.3048)
			(stroke
				(width 0.1)
				(type default)
			)
			(layer "F.Fab")
		)
		(fp_line
			(start 0.67945 -0.3048)
			(end 0.67945 0.3048)
			(stroke
				(width 0.1)
				(type default)
			)
			(layer "F.Fab")
		)
		(fp_line
			(start -0.67945 -0.305054)
			(end -0.12065 -0.305054)
			(stroke
				(width 0.1)
				(type default)
			)
			(layer "F.Fab")
		)
		(fp_line
			(start -0.12065 -0.305054)
			(end -0.12065 -0.2794)
			(stroke
				(width 0.1)
				(type default)
			)
			(layer "F.Fab")
		)
		(pad "1" smd circle
			(at -0.40005 0 270)
			(size 0 0)
			(layers "F.Cu" "F.Mask" "F.Paste")
			(net "PVCCIN_CPU1_PVCC")
		)
		(pad "2" smd circle
			(at 0.40005 0 270)
			(size 0 0)
			(layers "F.Cu" "F.Mask" "F.Paste")
			(net "GND")
		)
	)
	(footprint ""
		(layer "F.Cu")
		(at 75.416918 -18.164302)
		(property "Reference" "PR3805"
			(at 0 0 0)
			(layer "F.SilkS")
			(hide yes)
			(effects
				(font
					(size 1.27 1.27)
				)
			)
		)
		(property "Value" ""
			(at 0 0 0)
			(layer "F.Fab")
			(effects
				(font
					(size 1.27 1.27)
				)
			)
		)
		(duplicate_pad_numbers_are_jumpers no)
		(fp_line
			(start -0.7874 -0.4064)
			(end 0.7874 -0.4064)
			(stroke
				(width 0.1524)
				(type default)
			)
			(layer "F.SilkS")
		)
		(fp_line
			(start -0.7874 0.4064)
			(end -0.7874 -0.4064)
			(stroke
				(width 0.1524)
				(type default)
			)
			(layer "F.SilkS")
		)
		(fp_line
			(start 0.7874 -0.4064)
			(end 0.7874 0.4064)
			(stroke
				(width 0.1524)
				(type default)
			)
			(layer "F.SilkS")
		)
		(fp_line
			(start 0.7874 0.4064)
			(end -0.7874 0.4064)
			(stroke
				(width 0.1524)
				(type default)
			)
			(layer "F.SilkS")
		)
		(fp_line
			(start -0.67945 -0.305054)
			(end -0.12065 -0.305054)
			(stroke
				(width 0.1)
				(type default)
			)
			(layer "F.Fab")
		)
		(fp_line
			(start -0.67945 0.3048)
			(end -0.67945 -0.305054)
			(stroke
				(width 0.1)
				(type default)
			)
			(layer "F.Fab")
		)
		(fp_line
			(start -0.12065 -0.305054)
			(end -0.12065 -0.2794)
			(stroke
				(width 0.1)
				(type default)
			)
			(layer "F.Fab")
		)
		(fp_line
			(start -0.12065 -0.2794)
			(end 0.12065 -0.2794)
			(stroke
				(width 0.1)
				(type default)
			)
			(layer "F.Fab")
		)
		(fp_line
			(start -0.12065 0.2794)
			(end -0.12065 0.3048)
			(stroke
				(width 0.1)
				(type default)
			)
			(layer "F.Fab")
		)
		(fp_line
			(start -0.12065 0.3048)
			(end -0.67945 0.3048)
			(stroke
				(width 0.1)
				(type default)
			)
			(layer "F.Fab")
		)
		(fp_line
			(start 0.120396 0.2794)
			(end -0.12065 0.2794)
			(stroke
				(width 0.1)
				(type default)
			)
			(layer "F.Fab")
		)
		(fp_line
			(start 0.120396 0.3048)
			(end 0.120396 0.2794)
			(stroke
				(width 0.1)
				(type default)
			)
			(layer "F.Fab")
		)
		(fp_line
			(start 0.12065 -0.3048)
			(end 0.67945 -0.3048)
			(stroke
				(width 0.1)
				(type default)
			)
			(layer "F.Fab")
		)
		(fp_line
			(start 0.12065 -0.2794)
			(end 0.12065 -0.3048)
			(stroke
				(width 0.1)
				(type default)
			)
			(layer "F.Fab")
		)
		(fp_line
			(start 0.67945 -0.3048)
			(end 0.67945 0.3048)
			(stroke
				(width 0.1)
				(type default)
			)
			(layer "F.Fab")
		)
		(fp_line
			(start 0.67945 0.3048)
			(end 0.120396 0.3048)
			(stroke
				(width 0.1)
				(type default)
			)
			(layer "F.Fab")
		)
		(pad "1" smd circle
			(at -0.40005 0)
			(size 0 0)
			(layers "F.Cu" "F.Mask" "F.Paste")
			(net "P12V_AUX")
		)
		(pad "2" smd circle
			(at 0.40005 0)
			(size 0 0)
			(layers "F.Cu" "F.Mask" "F.Paste")
			(net "P12V_OCP_UV_2")
		)
	)
	(footprint ""
		(layer "F.Cu")
		(at 29.22524 -137.978388 90)
		(property "Reference" "PR4245"
			(at 0 0 90)
			(layer "F.SilkS")
			(hide yes)
			(effects
				(font
					(size 1.27 1.27)
				)
			)
		)
		(property "Value" ""
			(at 0 0 90)
			(layer "F.Fab")
			(effects
				(font
					(size 1.27 1.27)
				)
			)
		)
		(duplicate_pad_numbers_are_jumpers no)
		(fp_line
			(start 0.7874 -0.4064)
			(end 0.7874 0.4064)
			(stroke
				(width 0.1524)
				(type default)
			)
			(layer "F.SilkS")
		)
		(fp_line
			(start -0.7874 -0.4064)
			(end 0.7874 -0.4064)
			(stroke
				(width 0.1524)
				(type default)
			)
			(layer "F.SilkS")
		)
		(fp_line
			(start 0.7874 0.4064)
			(end -0.7874 0.4064)
			(stroke
				(width 0.1524)
				(type default)
			)
			(layer "F.SilkS")
		)
		(fp_line
			(start -0.7874 0.4064)
			(end -0.7874 -0.4064)
			(stroke
				(width 0.1524)
				(type default)
			)
			(layer "F.SilkS")
		)
		(fp_line
			(start -0.12065 -0.305054)
			(end -0.12065 -0.2794)
			(stroke
				(width 0.1)
				(type default)
			)
			(layer "F.Fab")
		)
		(fp_line
			(start -0.67945 -0.305054)
			(end -0.12065 -0.305054)
			(stroke
				(width 0.1)
				(type default)
			)
			(layer "F.Fab")
		)
		(fp_line
			(start 0.67945 -0.3048)
			(end 0.67945 0.3048)
			(stroke
				(width 0.1)
				(type default)
			)
			(layer "F.Fab")
		)
		(fp_line
			(start 0.12065 -0.3048)
			(end 0.67945 -0.3048)
			(stroke
				(width 0.1)
				(type default)
			)
			(layer "F.Fab")
		)
		(fp_line
			(start 0.12065 -0.2794)
			(end 0.12065 -0.3048)
			(stroke
				(width 0.1)
				(type default)
			)
			(layer "F.Fab")
		)
		(fp_line
			(start -0.12065 -0.2794)
			(end 0.12065 -0.2794)
			(stroke
				(width 0.1)
				(type default)
			)
			(layer "F.Fab")
		)
		(fp_line
			(start 0.120396 0.2794)
			(end -0.12065 0.2794)
			(stroke
				(width 0.1)
				(type default)
			)
			(layer "F.Fab")
		)
		(fp_line
			(start -0.12065 0.2794)
			(end -0.12065 0.3048)
			(stroke
				(width 0.1)
				(type default)
			)
			(layer "F.Fab")
		)
		(fp_line
			(start 0.67945 0.3048)
			(end 0.120396 0.3048)
			(stroke
				(width 0.1)
				(type default)
			)
			(layer "F.Fab")
		)
		(fp_line
			(start 0.120396 0.3048)
			(end 0.120396 0.2794)
			(stroke
				(width 0.1)
				(type default)
			)
			(layer "F.Fab")
		)
		(fp_line
			(start -0.12065 0.3048)
			(end -0.67945 0.3048)
			(stroke
				(width 0.1)
				(type default)
			)
			(layer "F.Fab")
		)
		(fp_line
			(start -0.67945 0.3048)
			(end -0.67945 -0.305054)
			(stroke
				(width 0.1)
				(type default)
			)
			(layer "F.Fab")
		)
		(pad "1" smd circle
			(at -0.40005 0 90)
			(size 0 0)
			(layers "F.Cu" "F.Mask" "F.Paste")
			(net "NC_PVCCINFAON_CPU1_ACSP6")
		)
		(pad "2" smd circle
			(at 0.40005 0 90)
			(size 0 0)
			(layers "F.Cu" "F.Mask" "F.Paste")
			(net "GND")
		)
	)
)
